# BASEBOARD_FAB2 (Tioga Pass) — schematic netlist excerpt (pin names and nets, part order shuffled) for the footprints in the layout excerpt that follows; sources: Cadence DE-HDL packaged netlist, KiCad conversion of Wiwynn_Tioga_Pass_MB.brd

EU8A2  RT9059  IC  pkg DFN  page 237
  VOUT(0)  = P1V8_PCH_STBY
  VOUT(1)  = P1V8_PCH_STBY
  VOUT(2)  = P1V8_PCH_STBY
  ADJ_NC  = VR_P1V8_PCH_STBY_FB
  PGOOD  = PWRGD_P1V8_PCH_STBY_R
  EN  = PWRGD_P3V3_STBY
  VIN(0)  = P3V3_STBY
  VIN(1)  = P3V3_STBY
  VIN(2)  = P3V3_STBY
  VDD  = P3V3_STBY
  GND  = GND

R2T40  RES  0.0 5% CHIP  pkg 0402  page 92 : A = H_CPU0_ERR2_G_N ; B = H_CPU_ERR2_G_R_N

(kicad_pcb
	(version 20260206)
	(generator "pcbnew")
	(generator_version "10.0")
	(general
		(thickness 1.6)
		(legacy_teardrops no)
	)
	(paper "A4")
	(title_block
		(title "Wiwynn_Tioga_Pass_MB.brd")
		(comment 1 "Tioga Pass / footprints 8-9 of 4770")
	)
	(layers
		(0 "F.Cu" signal "TOP")
		(4 "In1.Cu" signal "L2GND")
		(6 "In2.Cu" signal "L3")
		(8 "In3.Cu" signal "L4GND")
		(10 "In4.Cu" signal "L5")
		(12 "In5.Cu" signal "L6GND")
		(14 "In6.Cu" signal "L7VCC")
		(16 "In7.Cu" signal "L8VCC")
		(18 "In8.Cu" signal "L9GND")
		(20 "In9.Cu" signal "L10")
		(22 "In10.Cu" signal "L11GND")
		(24 "In11.Cu" signal "L12")
		(26 "In12.Cu" signal "L13GND")
		(2 "B.Cu" signal "BOTTOM")
		(9 "F.Adhes" user "F.Adhesive")
		(11 "B.Adhes" user "B.Adhesive")
		(13 "F.Paste" user "Package Geometry/Pastemask Top")
		(15 "B.Paste" user "Package Geometry/Pastemask Bottom")
		(5 "F.SilkS" user "Ref Des/Silkscreen Top")
		(7 "B.SilkS" user "Ref Des/Silkscreen Bottom")
		(1 "F.Mask" user "Board Geometry/Soldermask Top")
		(3 "B.Mask" user "Board Geometry/Soldermask Bottom")
		(17 "Dwgs.User" user "User.Drawings")
		(19 "Cmts.User" user "User.Comments")
		(21 "Eco1.User" user "User.Eco1")
		(23 "Eco2.User" user "User.Eco2")
		(25 "Edge.Cuts" user "Board Geometry/Outline")
		(27 "Margin" user)
		(31 "F.CrtYd" user "Package Geometry/Place Bound Top")
		(29 "B.CrtYd" user "Package Geometry/Place Bound Bottom")
		(35 "F.Fab" user "Ref Des/Assembly Top")
		(33 "B.Fab" user "Ref Des/Assembly Bottom")
	)
	(footprint ""
		(layer "F.Cu")
		(at 382.898904 -76.019406 180)
		(property "Reference" "R2T40"
			(at 0 0 180)
			(layer "F.SilkS")
			(hide yes)
			(effects
				(font
					(size 1.27 1.27)
				)
			)
		)
		(property "Value" ""
			(at 0 0 180)
			(layer "F.Fab")
			(effects
				(font
					(size 1.27 1.27)
				)
			)
		)
		(duplicate_pad_numbers_are_jumpers no)
		(fp_poly
			(pts
				(xy -0.2794 -0.1016) (xy 0.2794 -0.1016) (xy 0.2794 0.9906) (xy -0.2794 0.9906)
			)
			(stroke
				(width 0)
				(type default)
			)
			(fill no)
			(layer "F.CrtYd")
		)
		(fp_line
			(start 0.2794 0.9906)
			(end 0.2794 -0.1016)
			(stroke
				(width 0.1)
				(type default)
			)
			(layer "F.Fab")
		)
		(fp_line
			(start 0.2794 -0.1016)
			(end -0.2794 -0.1016)
			(stroke
				(width 0.1)
				(type default)
			)
			(layer "F.Fab")
		)
		(fp_line
			(start -0.2794 0.9906)
			(end 0.2794 0.9906)
			(stroke
				(width 0.1)
				(type default)
			)
			(layer "F.Fab")
		)
		(fp_line
			(start -0.2794 -0.1016)
			(end -0.2794 0.9906)
			(stroke
				(width 0.1)
				(type default)
			)
			(layer "F.Fab")
		)
		(pad "1" smd rect
			(at 0 0 180)
			(size 0.508 0.508)
			(layers "F.Cu" "F.Mask" "F.Paste")
			(net "H_CPU0_ERR2_G_N")
		)
		(pad "2" smd rect
			(at 0 0.889 180)
			(size 0.508 0.508)
			(layers "F.Cu" "F.Mask" "F.Paste")
			(net "H_CPU_ERR2_G_R_N")
		)
		(zone
			(layer "F.Cu")
			(hatch none 0.5)
			(connect_pads
				(clearance 0)
			)
			(min_thickness 0.25)
			(keepout
				(tracks not_allowed)
				(vias allowed)
				(pads allowed)
				(copperpour not_allowed)
				(footprints allowed)
			)
			(placement
				(enabled no)
				(sheetname "")
			)
			(fill
				(thermal_gap 0.5)
				(thermal_bridge_width 0.5)
				(island_removal_mode 0)
			)
			(polygon
				(pts
					(xy 383.152904 -76.654406) (xy 382.644904 -76.654406) (xy 382.644904 -76.273406) (xy 383.152904 -76.273406)
				)
			)
		)
		(zone
			(layer "F.Cu")
			(hatch none 0.5)
			(connect_pads
				(clearance 0)
			)
			(min_thickness 0.25)
			(keepout
				(tracks allowed)
				(vias not_allowed)
				(pads allowed)
				(copperpour not_allowed)
				(footprints allowed)
			)
			(placement
				(enabled no)
				(sheetname "")
			)
			(fill
				(thermal_gap 0.5)
				(thermal_bridge_width 0.5)
				(island_removal_mode 0)
			)
			(polygon
				(pts
					(xy 383.152904 -76.273406) (xy 382.644904 -76.273406) (xy 382.644904 -76.654406) (xy 383.152904 -76.654406)
				)
			)
		)
	)
	(footprint ""
		(layer "F.Cu")
		(at 401.752816 -147.928584 90)
		(property "Reference" "EU8A2"
			(at 0.228346 -5.106416 0)
			(unlocked yes)
			(layer "F.SilkS")
			(effects
				(font
					(size 0.7874 0.5842)
					(thickness 0.1524)
				)
				(justify left)
			)
		)
		(property "Value" ""
			(at 0 0 90)
			(layer "F.Fab")
			(effects
				(font
					(size 1.27 1.27)
				)
			)
		)
		(duplicate_pad_numbers_are_jumpers no)
		(fp_circle
			(center -0.835152 -0.417322)
			(end -0.835152 -0.290576)
			(stroke
				(width 0.254)
				(type default)
			)
			(fill no)
			(layer "F.SilkS")
		)
		(fp_poly
			(pts
				(xy -0.064516 -1.0922) (xy -0.064516 -0.3302) (xy 0.697484 -1.0922)
			)
			(stroke
				(width 0)
				(type default)
			)
			(fill yes)
			(layer "F.SilkS")
		)
		(fp_rect
			(start 0.597408 2.295398)
			(end 2.273808 -0.295402)
			(stroke
				(width 0)
				(type default)
			)
			(fill yes)
			(layer "F.Paste")
		)
		(fp_rect
			(start -0.064516 2.500122)
			(end 2.935478 -0.500126)
			(stroke
				(width 0)
				(type default)
			)
			(fill no)
			(layer "F.CrtYd")
		)
		(fp_line
			(start 2.935478 -0.500126)
			(end 2.935478 2.500122)
			(stroke
				(width 0.1)
				(type default)
			)
			(layer "F.Fab")
		)
		(fp_line
			(start -0.064516 -0.500126)
			(end 2.935478 -0.500126)
			(stroke
				(width 0.1)
				(type default)
			)
			(layer "F.Fab")
		)
		(fp_line
			(start 2.935478 2.500122)
			(end -0.064516 2.500122)
			(stroke
				(width 0.1)
				(type default)
			)
			(layer "F.Fab")
		)
		(fp_line
			(start -0.064516 2.500122)
			(end -0.064516 -0.500126)
			(stroke
				(width 0.1)
				(type default)
			)
			(layer "F.Fab")
		)
		(fp_circle
			(center -0.835152 -0.417322)
			(end -0.835152 -0.290576)
			(stroke
				(width 0.254)
				(type default)
			)
			(fill no)
			(layer "F.Fab")
		)
		(pad "1" smd rect
			(at 0 0 90)
			(size 0.6858 0.3048)
			(layers "F.Cu" "F.Mask" "F.Paste")
			(net "P1V8_PCH_STBY")
		)
		(pad "2" smd rect
			(at 0 0.500126 90)
			(size 0.6858 0.3048)
			(layers "F.Cu" "F.Mask" "F.Paste")
			(net "P1V8_PCH_STBY")
		)
		(pad "3" smd rect
			(at 0 0.999998 90)
			(size 0.6858 0.3048)
			(layers "F.Cu" "F.Mask" "F.Paste")
			(net "P1V8_PCH_STBY")
		)
		(pad "4" smd rect
			(at 0 1.500124 90)
			(size 0.6858 0.3048)
			(layers "F.Cu" "F.Mask" "F.Paste")
			(net "VR_P1V8_PCH_STBY_FB")
		)
		(pad "5" smd rect
			(at 0 1.999996 90)
			(size 0.6858 0.3048)
			(layers "F.Cu" "F.Mask" "F.Paste")
			(net "PWRGD_P1V8_PCH_STBY_R")
		)
		(pad "6" smd rect
			(at 2.871216 1.999996 90)
			(size 0.6858 0.3048)
			(layers "F.Cu" "F.Mask" "F.Paste")
			(net "PWRGD_P3V3_STBY")
		)
		(pad "7" smd rect
			(at 2.871216 1.500124 90)
			(size 0.6858 0.3048)
			(layers "F.Cu" "F.Mask" "F.Paste")
			(net "P3V3_STBY")
		)
		(pad "8" smd rect
			(at 2.871216 0.999998 90)
			(size 0.6858 0.3048)
			(layers "F.Cu" "F.Mask" "F.Paste")
			(net "P3V3_STBY")
		)
		(pad "9" smd rect
			(at 2.871216 0.500126 90)
			(size 0.6858 0.3048)
			(layers "F.Cu" "F.Mask" "F.Paste")
			(net "P3V3_STBY")
		)
		(pad "10" smd rect
			(at 2.871216 0 90)
			(size 0.6858 0.3048)
			(layers "F.Cu" "F.Mask" "F.Paste")
			(net "P3V3_STBY")
		)
		(pad "11" smd rect
			(at 1.435608 0.999998 90)
			(size 1.6764 2.5908)
			(layers "F.Cu" "F.Mask" "F.Paste")
			(net "GND")
		)
	)
)
